# S9S_MB_2U (Grand Teton) — schematic netlist excerpt (pin names and nets, part order shuffled) for the footprints in the layout excerpt that follows; sources: Cadence DE-HDL packaged netlist, KiCad conversion of 03242023_DA0F0TMBIJ0_F0T_Motherboard_J_brd_V01_OCP.brd

C2176  Q_CAP  100PF 50V 5% EMPTY  pkg 0402  page 250 : A = P12V_OCP_SFF_ISENSE_MAM ; B = GND
PR4222  Q_RES  0 5% CHIP  pkg 0402LF  page 274 : A = NC_PVCCINFAON_CPU0_ACSP4 ; B = GND

(kicad_pcb
	(version 20260206)
	(generator "pcbnew")
	(generator_version "10.0")
	(general
		(thickness 1.6)
		(legacy_teardrops no)
	)
	(paper "A4")
	(title_block
		(title "03242023_DA0F0TMBIJ0_F0T_Motherboard_J_brd_V01_OCP.brd")
		(comment 1 "Grand Teton / footprints 3040-3041 of 6105")
	)
	(layers
		(0 "F.Cu" signal "TOP")
		(4 "In1.Cu" signal "GND")
		(6 "In2.Cu" signal "IN1")
		(8 "In3.Cu" signal "GND1")
		(10 "In4.Cu" signal "IN2")
		(12 "In5.Cu" signal "GND2")
		(14 "In6.Cu" signal "IN3")
		(16 "In7.Cu" signal "GND3")
		(18 "In8.Cu" signal "VCC")
		(20 "In9.Cu" signal "VCC1")
		(22 "In10.Cu" signal "GND4")
		(24 "In11.Cu" signal "IN4")
		(26 "In12.Cu" signal "GND5")
		(28 "In13.Cu" signal "IN5")
		(30 "In14.Cu" signal "GND6")
		(32 "In15.Cu" signal "IN6")
		(34 "In16.Cu" signal "GND7")
		(2 "B.Cu" signal "BOTTOM")
		(9 "F.Adhes" user "F.Adhesive")
		(11 "B.Adhes" user "B.Adhesive")
		(13 "F.Paste" user "Package Geometry/Pastemask Top")
		(15 "B.Paste" user "Package Geometry/Pastemask Bottom")
		(5 "F.SilkS" user "Ref Des/Silkscreen Top")
		(7 "B.SilkS" user "Ref Des/Silkscreen Bottom")
		(1 "F.Mask" user "Board Geometry/Soldermask Top")
		(3 "B.Mask" user "Board Geometry/Soldermask Bottom")
		(17 "Dwgs.User" user "User.Drawings")
		(19 "Cmts.User" user "User.Comments")
		(21 "Eco1.User" user "User.Eco1")
		(23 "Eco2.User" user "User.Eco2")
		(25 "Edge.Cuts" user "Board Geometry/Outline")
		(27 "Margin" user)
		(31 "F.CrtYd" user "Package Geometry/Place Bound Top")
		(29 "B.CrtYd" user "Package Geometry/Place Bound Bottom")
		(35 "F.Fab" user "Ref Des/Assembly Top")
		(33 "B.Fab" user "Ref Des/Assembly Bottom")
	)
	(footprint ""
		(layer "F.Cu")
		(at 32.761428 -99.586034 180)
		(property "Reference" "C2176"
			(at 0 0 180)
			(layer "F.SilkS")
			(hide yes)
			(effects
				(font
					(size 1.27 1.27)
				)
			)
		)
		(property "Value" ""
			(at 0 0 180)
			(layer "F.Fab")
			(effects
				(font
					(size 1.27 1.27)
				)
			)
		)
		(duplicate_pad_numbers_are_jumpers no)
		(fp_line
			(start 0.7874 0.4064)
			(end -0.7874 0.4064)
			(stroke
				(width 0.1524)
				(type default)
			)
			(layer "F.SilkS")
		)
		(fp_line
			(start 0.7874 -0.4064)
			(end 0.7874 0.4064)
			(stroke
				(width 0.1524)
				(type default)
			)
			(layer "F.SilkS")
		)
		(fp_line
			(start -0.7874 0.4064)
			(end -0.7874 -0.4064)
			(stroke
				(width 0.1524)
				(type default)
			)
			(layer "F.SilkS")
		)
		(fp_line
			(start -0.7874 -0.4064)
			(end 0.7874 -0.4064)
			(stroke
				(width 0.1524)
				(type default)
			)
			(layer "F.SilkS")
		)
		(fp_line
			(start 0.67945 0.3048)
			(end 0.120396 0.3048)
			(stroke
				(width 0.1)
				(type default)
			)
			(layer "F.Fab")
		)
		(fp_line
			(start 0.67945 -0.3048)
			(end 0.67945 0.3048)
			(stroke
				(width 0.1)
				(type default)
			)
			(layer "F.Fab")
		)
		(fp_line
			(start 0.12065 -0.2794)
			(end 0.12065 -0.3048)
			(stroke
				(width 0.1)
				(type default)
			)
			(layer "F.Fab")
		)
		(fp_line
			(start 0.12065 -0.3048)
			(end 0.67945 -0.3048)
			(stroke
				(width 0.1)
				(type default)
			)
			(layer "F.Fab")
		)
		(fp_line
			(start 0.120396 0.3048)
			(end 0.120396 0.2794)
			(stroke
				(width 0.1)
				(type default)
			)
			(layer "F.Fab")
		)
		(fp_line
			(start 0.120396 0.2794)
			(end -0.12065 0.2794)
			(stroke
				(width 0.1)
				(type default)
			)
			(layer "F.Fab")
		)
		(fp_line
			(start -0.12065 0.3048)
			(end -0.67945 0.3048)
			(stroke
				(width 0.1)
				(type default)
			)
			(layer "F.Fab")
		)
		(fp_line
			(start -0.12065 0.2794)
			(end -0.12065 0.3048)
			(stroke
				(width 0.1)
				(type default)
			)
			(layer "F.Fab")
		)
		(fp_line
			(start -0.12065 -0.2794)
			(end 0.12065 -0.2794)
			(stroke
				(width 0.1)
				(type default)
			)
			(layer "F.Fab")
		)
		(fp_line
			(start -0.12065 -0.305054)
			(end -0.12065 -0.2794)
			(stroke
				(width 0.1)
				(type default)
			)
			(layer "F.Fab")
		)
		(fp_line
			(start -0.67945 0.3048)
			(end -0.67945 -0.305054)
			(stroke
				(width 0.1)
				(type default)
			)
			(layer "F.Fab")
		)
		(fp_line
			(start -0.67945 -0.305054)
			(end -0.12065 -0.305054)
			(stroke
				(width 0.1)
				(type default)
			)
			(layer "F.Fab")
		)
		(pad "1" smd circle
			(at -0.40005 0 180)
			(size 0 0)
			(layers "F.Cu" "F.Mask" "F.Paste")
			(net "P12V_OCP_SFF_ISENSE_MAM")
		)
		(pad "2" smd circle
			(at 0.40005 0 180)
			(size 0 0)
			(layers "F.Cu" "F.Mask" "F.Paste")
			(net "GND")
		)
	)
	(footprint ""
		(layer "F.Cu")
		(at 425.71416 -143.675608 90)
		(property "Reference" "PR4222"
			(at 0 0 90)
			(layer "F.SilkS")
			(hide yes)
			(effects
				(font
					(size 1.27 1.27)
				)
			)
		)
		(property "Value" ""
			(at 0 0 90)
			(layer "F.Fab")
			(effects
				(font
					(size 1.27 1.27)
				)
			)
		)
		(duplicate_pad_numbers_are_jumpers no)
		(fp_line
			(start 0.7874 -0.4064)
			(end 0.7874 0.4064)
			(stroke
				(width 0.1524)
				(type default)
			)
			(layer "F.SilkS")
		)
		(fp_line
			(start -0.7874 -0.4064)
			(end 0.7874 -0.4064)
			(stroke
				(width 0.1524)
				(type default)
			)
			(layer "F.SilkS")
		)
		(fp_line
			(start 0.7874 0.4064)
			(end -0.7874 0.4064)
			(stroke
				(width 0.1524)
				(type default)
			)
			(layer "F.SilkS")
		)
		(fp_line
			(start -0.7874 0.4064)
			(end -0.7874 -0.4064)
			(stroke
				(width 0.1524)
				(type default)
			)
			(layer "F.SilkS")
		)
		(fp_line
			(start -0.12065 -0.305054)
			(end -0.12065 -0.2794)
			(stroke
				(width 0.1)
				(type default)
			)
			(layer "F.Fab")
		)
		(fp_line
			(start -0.67945 -0.305054)
			(end -0.12065 -0.305054)
			(stroke
				(width 0.1)
				(type default)
			)
			(layer "F.Fab")
		)
		(fp_line
			(start 0.67945 -0.3048)
			(end 0.67945 0.3048)
			(stroke
				(width 0.1)
				(type default)
			)
			(layer "F.Fab")
		)
		(fp_line
			(start 0.12065 -0.3048)
			(end 0.67945 -0.3048)
			(stroke
				(width 0.1)
				(type default)
			)
			(layer "F.Fab")
		)
		(fp_line
			(start 0.12065 -0.2794)
			(end 0.12065 -0.3048)
			(stroke
				(width 0.1)
				(type default)
			)
			(layer "F.Fab")
		)
		(fp_line
			(start -0.12065 -0.2794)
			(end 0.12065 -0.2794)
			(stroke
				(width 0.1)
				(type default)
			)
			(layer "F.Fab")
		)
		(fp_line
			(start 0.120396 0.2794)
			(end -0.12065 0.2794)
			(stroke
				(width 0.1)
				(type default)
			)
			(layer "F.Fab")
		)
		(fp_line
			(start -0.12065 0.2794)
			(end -0.12065 0.3048)
			(stroke
				(width 0.1)
				(type default)
			)
			(layer "F.Fab")
		)
		(fp_line
			(start 0.67945 0.3048)
			(end 0.120396 0.3048)
			(stroke
				(width 0.1)
				(type default)
			)
			(layer "F.Fab")
		)
		(fp_line
			(start 0.120396 0.3048)
			(end 0.120396 0.2794)
			(stroke
				(width 0.1)
				(type default)
			)
			(layer "F.Fab")
		)
		(fp_line
			(start -0.12065 0.3048)
			(end -0.67945 0.3048)
			(stroke
				(width 0.1)
				(type default)
			)
			(layer "F.Fab")
		)
		(fp_line
			(start -0.67945 0.3048)
			(end -0.67945 -0.305054)
			(stroke
				(width 0.1)
				(type default)
			)
			(layer "F.Fab")
		)
		(pad "1" smd circle
			(at -0.40005 0 90)
			(size 0 0)
			(layers "F.Cu" "F.Mask" "F.Paste")
			(net "NC_PVCCINFAON_CPU0_ACSP4")
		)
		(pad "2" smd circle
			(at 0.40005 0 90)
			(size 0 0)
			(layers "F.Cu" "F.Mask" "F.Paste")
			(net "GND")
		)
	)
)
